(kicad_pcb
	(version 20260206)
	(generator "pcbnew")
	(generator_version "10.0")
	(general
		(thickness 1.6)
		(legacy_teardrops no)
	)
	(paper "A4")
	(title_block
		(title "panther-plus-userver — 13130-1b_20150205.brd")
		(comment 1 "Honey Badger (Wiwynn) / footprints 1273-1281 of 1509")
	)
	(layers
		(0 "F.Cu" signal "TOP")
		(4 "In1.Cu" signal "L2")
		(6 "In2.Cu" signal "L3")
		(8 "In3.Cu" signal "L4")
		(10 "In4.Cu" signal "L5")
		(12 "In5.Cu" signal "L6")
		(14 "In6.Cu" signal "L7")
		(16 "In7.Cu" signal "L8")
		(18 "In8.Cu" signal "L9")
		(20 "In9.Cu" signal "L10")
		(22 "In10.Cu" signal "L11")
		(2 "B.Cu" signal "BOTTOM")
		(9 "F.Adhes" user "F.Adhesive")
		(11 "B.Adhes" user "B.Adhesive")
		(13 "F.Paste" user "Package Geometry/Pastemask Top")
		(15 "B.Paste" user "Package Geometry/Pastemask Bottom")
		(5 "F.SilkS" user "Ref Des/Silkscreen Top")
		(7 "B.SilkS" user "Ref Des/Silkscreen Bottom")
		(1 "F.Mask" user "Board Geometry/Soldermask Top")
		(3 "B.Mask" user "Board Geometry/Soldermask Bottom")
		(17 "Dwgs.User" user "User.Drawings")
		(19 "Cmts.User" user "User.Comments")
		(21 "Eco1.User" user "User.Eco1")
		(23 "Eco2.User" user "User.Eco2")
		(25 "Edge.Cuts" user "Board Geometry/Outline")
		(27 "Margin" user)
		(31 "F.CrtYd" user "Package Geometry/Place Bound Top")
		(29 "B.CrtYd" user "Package Geometry/Place Bound Bottom")
		(35 "F.Fab" user "Ref Des/Assembly Top")
		(33 "B.Fab" user "Ref Des/Assembly Bottom")
	)
	(footprint ""
		(layer "B.Cu")
		(at 145.669 -44.958 180)
		(property "Reference" "R77"
			(at 0 0 0)
			(layer "B.SilkS")
			(hide yes)
			(effects
				(font
					(size 1.27 1.27)
				)
				(justify mirror)
			)
		)
		(property "Value" "10KR2F-2-GP"
			(at -0.064008 -3.993896 180)
			(unlocked yes)
			(layer "B.Fab")
			(hide yes)
			(effects
				(font
					(size 1.016 1.016)
					(thickness 0.1524)
				)
				(justify mirror)
			)
		)
		(property "Device Type" "R402H16"
			(at -0.064008 -5.517896 180)
			(unlocked yes)
			(layer "B.Fab")
			(hide yes)
			(effects
				(font
					(size 1.016 1.016)
					(thickness 0.1524)
				)
				(justify mirror)
			)
		)
		(duplicate_pad_numbers_are_jumpers no)
		(fp_rect
			(start 0.381 0.8382)
			(end -0.381 -0.8382)
			(stroke
				(width 0)
				(type default)
			)
			(fill no)
			(layer "B.CrtYd")
		)
		(fp_rect
			(start 0.381 0.8382)
			(end -0.381 -0.8382)
			(stroke
				(width 0)
				(type default)
			)
			(fill no)
			(layer "B.Fab")
		)
		(pad "1" smd custom
			(at 0 -0.4318)
			(size 0.127 0.127)
			(layers "B.Cu" "B.Mask" "B.Paste")
			(net "P3V3_STBY")
			(options
				(clearance outline)
				(anchor circle)
			)
			(primitives
				(gr_poly
					(pts
						(arc
							(start -0.2032 0.2794)
							(mid -0.239121 0.264521)
							(end -0.254 0.2286)
						)
						(arc
							(start -0.254 -0.2286)
							(mid -0.239121 -0.264521)
							(end -0.2032 -0.2794)
						)
						(arc
							(start 0.2032 -0.2794)
							(mid 0.239121 -0.264521)
							(end 0.254 -0.2286)
						)
						(arc
							(start 0.254 0.2286)
							(mid 0.239121 0.264521)
							(end 0.2032 0.2794)
						)
					)
					(width 0)
					(fill yes)
				)
			)
		)
		(pad "2" smd custom
			(at 0 0.4318)
			(size 0.127 0.127)
			(layers "B.Cu" "B.Mask" "B.Paste")
			(net "JTAG_PLD_TDI")
			(options
				(clearance outline)
				(anchor circle)
			)
			(primitives
				(gr_poly
					(pts
						(arc
							(start -0.2032 0.2794)
							(mid -0.239121 0.264521)
							(end -0.254 0.2286)
						)
						(arc
							(start -0.254 -0.2286)
							(mid -0.239121 -0.264521)
							(end -0.2032 -0.2794)
						)
						(arc
							(start 0.2032 -0.2794)
							(mid 0.239121 -0.264521)
							(end 0.254 -0.2286)
						)
						(arc
							(start 0.254 0.2286)
							(mid 0.239121 0.264521)
							(end 0.2032 0.2794)
						)
					)
					(width 0)
					(fill yes)
				)
			)
		)
	)
	(footprint ""
		(layer "B.Cu")
		(at 103.378 -27.321002)
		(property "Reference" "C243"
			(at 0 0 0)
			(layer "B.SilkS")
			(hide yes)
			(effects
				(font
					(size 1.27 1.27)
				)
				(justify mirror)
			)
		)
		(property "Value" "SC1U10V2KX-1GP"
			(at -1.1811 -2.7051 0)
			(unlocked yes)
			(layer "B.Fab")
			(hide yes)
			(effects
				(font
					(size 1.016 1.016)
					(thickness 0.1524)
				)
				(justify mirror)
			)
		)
		(property "Device Type" "C402H22"
			(at -1.1811 -4.2291 0)
			(unlocked yes)
			(layer "B.Fab")
			(hide yes)
			(effects
				(font
					(size 1.016 1.016)
					(thickness 0.1524)
				)
				(justify mirror)
			)
		)
		(duplicate_pad_numbers_are_jumpers no)
		(fp_rect
			(start 0.381 0.7366)
			(end -0.381 -0.7366)
			(stroke
				(width 0)
				(type default)
			)
			(fill no)
			(layer "B.CrtYd")
		)
		(fp_rect
			(start 0.381 0.7366)
			(end -0.381 -0.7366)
			(stroke
				(width 0)
				(type default)
			)
			(fill no)
			(layer "B.Fab")
		)
		(pad "1" smd custom
			(at 0 -0.4572 180)
			(size 0.1143 0.1143)
			(layers "B.Cu" "B.Mask" "B.Paste")
			(net "PV_VDDR")
			(options
				(clearance outline)
				(anchor circle)
			)
			(primitives
				(gr_poly
					(pts
						(arc
							(start -0.254 0.1778)
							(mid -0.239121 0.213721)
							(end -0.2032 0.2286)
						)
						(arc
							(start 0.2032 0.2286)
							(mid 0.239121 0.213721)
							(end 0.254 0.1778)
						)
						(arc
							(start 0.254 -0.1778)
							(mid 0.239121 -0.213721)
							(end 0.2032 -0.2286)
						)
						(arc
							(start -0.2032 -0.2286)
							(mid -0.239121 -0.213721)
							(end -0.254 -0.1778)
						)
					)
					(width 0)
					(fill yes)
				)
			)
		)
		(pad "2" smd custom
			(at 0 0.4572 180)
			(size 0.1143 0.1143)
			(layers "B.Cu" "B.Mask" "B.Paste")
			(net "GND")
			(options
				(clearance outline)
				(anchor circle)
			)
			(primitives
				(gr_poly
					(pts
						(arc
							(start -0.254 0.1778)
							(mid -0.239121 0.213721)
							(end -0.2032 0.2286)
						)
						(arc
							(start 0.2032 0.2286)
							(mid 0.239121 0.213721)
							(end 0.254 0.1778)
						)
						(arc
							(start 0.254 -0.1778)
							(mid 0.239121 -0.213721)
							(end 0.2032 -0.2286)
						)
						(arc
							(start -0.2032 -0.2286)
							(mid -0.239121 -0.213721)
							(end -0.254 -0.1778)
						)
					)
					(width 0)
					(fill yes)
				)
			)
		)
	)
	(footprint ""
		(layer "B.Cu")
		(at 27.813 -43.053)
		(property "Reference" "PC134"
			(at 0 0 0)
			(layer "B.SilkS")
			(hide yes)
			(effects
				(font
					(size 1.27 1.27)
				)
				(justify mirror)
			)
		)
		(property "Value" "SC10U6D3V5KX-4GP"
			(at 0 -4.9022 0)
			(unlocked yes)
			(layer "B.Fab")
			(hide yes)
			(effects
				(font
					(size 1.016 1.016)
					(thickness 0.1524)
				)
				(justify mirror)
			)
		)
		(property "Device Type" "C805H58"
			(at 0 -6.8072 0)
			(unlocked yes)
			(layer "B.Fab")
			(hide yes)
			(effects
				(font
					(size 1.016 1.016)
					(thickness 0.1524)
				)
				(justify mirror)
			)
		)
		(duplicate_pad_numbers_are_jumpers no)
		(fp_line
			(start -0.6096 0)
			(end 0.6096 0)
			(stroke
				(width 0.3048)
				(type default)
			)
			(layer "B.SilkS")
		)
		(fp_poly
			(pts
				(xy 0.9017 1.4351) (xy -0.9017 1.4351) (xy -0.9017 -1.4351) (xy 0.9017 -1.4351)
			)
			(stroke
				(width 0)
				(type default)
			)
			(fill no)
			(layer "B.CrtYd")
		)
		(fp_poly
			(pts
				(xy -0.9017 1.4351) (xy -0.9017 -1.4351) (xy 0.9017 -1.4351) (xy 0.9017 1.4351)
			)
			(stroke
				(width 0)
				(type default)
			)
			(fill no)
			(layer "B.Fab")
		)
		(pad "1" smd rect
			(at 0 -0.8382 180)
			(size 1.5494 0.9398)
			(layers "B.Cu" "B.Mask" "B.Paste")
			(net "P1V5_STBY_OUT")
		)
		(pad "2" smd rect
			(at 0 0.8382 180)
			(size 1.5494 0.9398)
			(layers "B.Cu" "B.Mask" "B.Paste")
			(net "GND")
		)
	)
	(footprint ""
		(layer "B.Cu")
		(at 92.71 -67.564)
		(property "Reference" "PC19"
			(at 0 0 0)
			(layer "B.SilkS")
			(hide yes)
			(effects
				(font
					(size 1.27 1.27)
				)
				(justify mirror)
			)
		)
		(property "Value" "SC22U10V6KX-GP"
			(at 0.0762 -5.1308 0)
			(unlocked yes)
			(layer "B.Fab")
			(hide yes)
			(effects
				(font
					(size 1.016 1.016)
					(thickness 0.1524)
				)
				(justify mirror)
			)
		)
		(property "Device Type" "C1206H71"
			(at 0.127 -6.6548 0)
			(unlocked yes)
			(layer "B.Fab")
			(hide yes)
			(effects
				(font
					(size 1.016 1.016)
					(thickness 0.1524)
				)
				(justify mirror)
			)
		)
		(duplicate_pad_numbers_are_jumpers no)
		(fp_rect
			(start 1.0541 1.9812)
			(end -1.0541 -1.9812)
			(stroke
				(width 0)
				(type default)
			)
			(fill no)
			(layer "B.CrtYd")
		)
		(fp_rect
			(start 1.0541 1.9812)
			(end -1.0541 -1.9812)
			(stroke
				(width 0)
				(type default)
			)
			(fill no)
			(layer "B.Fab")
		)
		(pad "1" smd rect
			(at 0 -1.3462 180)
			(size 1.8542 1.016)
			(layers "B.Cu" "B.Mask" "B.Paste")
			(net "VR_P1V1_PVIN")
		)
		(pad "2" smd rect
			(at 0 1.3462 180)
			(size 1.8542 1.016)
			(layers "B.Cu" "B.Mask" "B.Paste")
			(net "GND")
		)
	)
	(footprint ""
		(layer "B.Cu")
		(at 31.877 -33.6804)
		(property "Reference" "TP61"
			(at 0 0 0)
			(layer "B.SilkS")
			(hide yes)
			(effects
				(font
					(size 1.27 1.27)
				)
				(justify mirror)
			)
		)
		(property "Value" "TPAD32-GP"
			(at 0 -3.166364 0)
			(unlocked yes)
			(layer "B.Fab")
			(hide yes)
			(effects
				(font
					(size 1.016 1.016)
					(thickness 0.1524)
				)
				(justify mirror)
			)
		)
		(property "Device Type" "TPAD32"
			(at 0 -4.690618 0)
			(unlocked yes)
			(layer "B.Fab")
			(hide yes)
			(effects
				(font
					(size 1.016 1.016)
					(thickness 0.1524)
				)
				(justify mirror)
			)
		)
		(duplicate_pad_numbers_are_jumpers no)
		(fp_poly
			(pts
				(arc
					(start 0.7112 0)
					(mid -0.7112 0)
					(end 0.7112 0)
				)
			)
			(stroke
				(width 0)
				(type default)
			)
			(fill no)
			(layer "B.CrtYd")
		)
		(fp_poly
			(pts
				(arc
					(start 0.7112 0)
					(mid -0.7112 0)
					(end 0.7112 0)
				)
			)
			(stroke
				(width 0)
				(type default)
			)
			(fill no)
			(layer "B.Fab")
		)
		(pad "1" smd circle
			(at 0 0 180)
			(size 0.8128 0.8128)
			(layers "B.Cu" "B.Mask" "B.Paste")
			(net "XDP_SOC_CPU_TDO")
		)
	)
	(footprint ""
		(layer "B.Cu")
		(at 98.933 -40.071802)
		(property "Reference" "C180"
			(at 0 0 0)
			(layer "B.SilkS")
			(hide yes)
			(effects
				(font
					(size 1.27 1.27)
				)
				(justify mirror)
			)
		)
		(property "Value" "SC1U10V2KX-1GP"
			(at -1.1811 -2.7051 0)
			(unlocked yes)
			(layer "B.Fab")
			(hide yes)
			(effects
				(font
					(size 1.016 1.016)
					(thickness 0.1524)
				)
				(justify mirror)
			)
		)
		(property "Device Type" "C402H22"
			(at -1.1811 -4.2291 0)
			(unlocked yes)
			(layer "B.Fab")
			(hide yes)
			(effects
				(font
					(size 1.016 1.016)
					(thickness 0.1524)
				)
				(justify mirror)
			)
		)
		(duplicate_pad_numbers_are_jumpers no)
		(fp_rect
			(start 0.381 0.7366)
			(end -0.381 -0.7366)
			(stroke
				(width 0)
				(type default)
			)
			(fill no)
			(layer "B.CrtYd")
		)
		(fp_rect
			(start 0.381 0.7366)
			(end -0.381 -0.7366)
			(stroke
				(width 0)
				(type default)
			)
			(fill no)
			(layer "B.Fab")
		)
		(pad "1" smd custom
			(at 0 -0.4572 180)
			(size 0.1143 0.1143)
			(layers "B.Cu" "B.Mask" "B.Paste")
			(net "P1V0")
			(options
				(clearance outline)
				(anchor circle)
			)
			(primitives
				(gr_poly
					(pts
						(arc
							(start -0.254 0.1778)
							(mid -0.239121 0.213721)
							(end -0.2032 0.2286)
						)
						(arc
							(start 0.2032 0.2286)
							(mid 0.239121 0.213721)
							(end 0.254 0.1778)
						)
						(arc
							(start 0.254 -0.1778)
							(mid 0.239121 -0.213721)
							(end 0.2032 -0.2286)
						)
						(arc
							(start -0.2032 -0.2286)
							(mid -0.239121 -0.213721)
							(end -0.254 -0.1778)
						)
					)
					(width 0)
					(fill yes)
				)
			)
		)
		(pad "2" smd custom
			(at 0 0.4572 180)
			(size 0.1143 0.1143)
			(layers "B.Cu" "B.Mask" "B.Paste")
			(net "GND")
			(options
				(clearance outline)
				(anchor circle)
			)
			(primitives
				(gr_poly
					(pts
						(arc
							(start -0.254 0.1778)
							(mid -0.239121 0.213721)
							(end -0.2032 0.2286)
						)
						(arc
							(start 0.2032 0.2286)
							(mid 0.239121 0.213721)
							(end 0.254 0.1778)
						)
						(arc
							(start 0.254 -0.1778)
							(mid 0.239121 -0.213721)
							(end 0.2032 -0.2286)
						)
						(arc
							(start -0.2032 -0.2286)
							(mid -0.239121 -0.213721)
							(end -0.254 -0.1778)
						)
					)
					(width 0)
					(fill yes)
				)
			)
		)
	)
	(footprint ""
		(layer "B.Cu")
		(at 86.106 -19.939 -90)
		(property "Reference" "PC197"
			(at 0 0 90)
			(layer "B.SilkS")
			(hide yes)
			(effects
				(font
					(size 1.27 1.27)
				)
				(justify mirror)
			)
		)
		(property "Value" "SC1KP50V2KX-1GP"
			(at -1.1811 -2.7051 270)
			(unlocked yes)
			(layer "B.Fab")
			(hide yes)
			(effects
				(font
					(size 1.016 1.016)
					(thickness 0.1524)
				)
				(justify mirror)
			)
		)
		(property "Device Type" "C402H22"
			(at -1.1811 -4.2291 270)
			(unlocked yes)
			(layer "B.Fab")
			(hide yes)
			(effects
				(font
					(size 1.016 1.016)
					(thickness 0.1524)
				)
				(justify mirror)
			)
		)
		(duplicate_pad_numbers_are_jumpers no)
		(fp_rect
			(start 0.381 0.7366)
			(end -0.381 -0.7366)
			(stroke
				(width 0)
				(type default)
			)
			(fill no)
			(layer "B.CrtYd")
		)
		(fp_rect
			(start 0.381 0.7366)
			(end -0.381 -0.7366)
			(stroke
				(width 0)
				(type default)
			)
			(fill no)
			(layer "B.Fab")
		)
		(pad "1" smd custom
			(at 0 -0.4572 90)
			(size 0.1143 0.1143)
			(layers "B.Cu" "B.Mask" "B.Paste")
			(net "TPS74801_1V35_OUT")
			(options
				(clearance outline)
				(anchor circle)
			)
			(primitives
				(gr_poly
					(pts
						(arc
							(start -0.254 0.1778)
							(mid -0.239121 0.213721)
							(end -0.2032 0.2286)
						)
						(arc
							(start 0.2032 0.2286)
							(mid 0.239121 0.213721)
							(end 0.254 0.1778)
						)
						(arc
							(start 0.254 -0.1778)
							(mid 0.239121 -0.213721)
							(end 0.2032 -0.2286)
						)
						(arc
							(start -0.2032 -0.2286)
							(mid -0.239121 -0.213721)
							(end -0.254 -0.1778)
						)
					)
					(width 0)
					(fill yes)
				)
			)
		)
		(pad "2" smd custom
			(at 0 0.4572 90)
			(size 0.1143 0.1143)
			(layers "B.Cu" "B.Mask" "B.Paste")
			(net "TPS74801_1V35_FB")
			(options
				(clearance outline)
				(anchor circle)
			)
			(primitives
				(gr_poly
					(pts
						(arc
							(start -0.254 0.1778)
							(mid -0.239121 0.213721)
							(end -0.2032 0.2286)
						)
						(arc
							(start 0.2032 0.2286)
							(mid 0.239121 0.213721)
							(end 0.254 0.1778)
						)
						(arc
							(start 0.254 -0.1778)
							(mid 0.239121 -0.213721)
							(end 0.2032 -0.2286)
						)
						(arc
							(start -0.2032 -0.2286)
							(mid -0.239121 -0.213721)
							(end -0.254 -0.1778)
						)
					)
					(width 0)
					(fill yes)
				)
			)
		)
	)
	(footprint ""
		(layer "B.Cu")
		(at 85.852 -43.561 -90)
		(property "Reference" "TP25"
			(at 0 0 90)
			(layer "B.SilkS")
			(hide yes)
			(effects
				(font
					(size 1.27 1.27)
				)
				(justify mirror)
			)
		)
		(property "Value" "TPAD24"
			(at 0 -2.9972 270)
			(unlocked yes)
			(layer "B.Fab")
			(hide yes)
			(effects
				(font
					(size 1.016 1.016)
					(thickness 0.1524)
				)
				(justify mirror)
			)
		)
		(property "Device Type" "TPAD24"
			(at 0 -4.5212 270)
			(unlocked yes)
			(layer "B.Fab")
			(hide yes)
			(effects
				(font
					(size 1.016 1.016)
					(thickness 0.1524)
				)
				(justify mirror)
			)
		)
		(duplicate_pad_numbers_are_jumpers no)
		(fp_poly
			(pts
				(arc
					(start 0 -0.3048)
					(mid 0 0.3048)
					(end 0 -0.3048)
				)
			)
			(stroke
				(width 0)
				(type default)
			)
			(fill no)
			(layer "B.CrtYd")
		)
		(fp_poly
			(pts
				(arc
					(start 0 -0.6096)
					(mid 0 0.6096)
					(end 0 -0.6096)
				)
			)
			(stroke
				(width 0)
				(type default)
			)
			(fill no)
			(layer "B.Fab")
		)
		(pad "1" smd circle
			(at 0 0 90)
			(size 0.6096 0.6096)
			(layers "B.Cu" "B.Mask" "B.Paste")
			(net "TP_CPU_RSVD1")
		)
	)
	(footprint ""
		(layer "B.Cu")
		(at 186.6138 -28.4226 90)
		(property "Reference" "PC189"
			(at 0 0 90)
			(layer "B.SilkS")
			(hide yes)
			(effects
				(font
					(size 1.27 1.27)
				)
				(justify mirror)
			)
		)
		(property "Value" "SCD33U6D3V2KX-1-GP"
			(at -1.8923 -1.2065 90)
			(unlocked yes)
			(layer "B.Fab")
			(hide yes)
			(effects
				(font
					(size 1.016 1.016)
					(thickness 0.1524)
				)
				(justify mirror)
			)
		)
		(property "Device Type" "C402H22"
			(at -1.8923 -2.7305 90)
			(unlocked yes)
			(layer "B.Fab")
			(hide yes)
			(effects
				(font
					(size 1.016 1.016)
					(thickness 0.1524)
				)
				(justify mirror)
			)
		)
		(duplicate_pad_numbers_are_jumpers no)
		(fp_rect
			(start 0.381 0.7366)
			(end -0.381 -0.7366)
			(stroke
				(width 0)
				(type default)
			)
			(fill no)
			(layer "B.CrtYd")
		)
		(fp_rect
			(start 0.381 0.7366)
			(end -0.381 -0.7366)
			(stroke
				(width 0)
				(type default)
			)
			(fill no)
			(layer "B.Fab")
		)
		(pad "1" smd custom
			(at 0 -0.4572 270)
			(size 0.1143 0.1143)
			(layers "B.Cu" "B.Mask" "B.Paste")
			(net "VR_PVDDRA_ISUMP1")
			(options
				(clearance outline)
				(anchor circle)
			)
			(primitives
				(gr_poly
					(pts
						(arc
							(start -0.254 0.1778)
							(mid -0.239121 0.213721)
							(end -0.2032 0.2286)
						)
						(arc
							(start 0.2032 0.2286)
							(mid 0.239121 0.213721)
							(end 0.254 0.1778)
						)
						(arc
							(start 0.254 -0.1778)
							(mid 0.239121 -0.213721)
							(end 0.2032 -0.2286)
						)
						(arc
							(start -0.2032 -0.2286)
							(mid -0.239121 -0.213721)
							(end -0.254 -0.1778)
						)
					)
					(width 0)
					(fill yes)
				)
			)
		)
		(pad "2" smd custom
			(at 0 0.4572 270)
			(size 0.1143 0.1143)
			(layers "B.Cu" "B.Mask" "B.Paste")
			(net "VR_PVDDRA_ISUMN1")
			(options
				(clearance outline)
				(anchor circle)
			)
			(primitives
				(gr_poly
					(pts
						(arc
							(start -0.254 0.1778)
							(mid -0.239121 0.213721)
							(end -0.2032 0.2286)
						)
						(arc
							(start 0.2032 0.2286)
							(mid 0.239121 0.213721)
							(end 0.254 0.1778)
						)
						(arc
							(start 0.254 -0.1778)
							(mid 0.239121 -0.213721)
							(end 0.2032 -0.2286)
						)
						(arc
							(start -0.2032 -0.2286)
							(mid -0.239121 -0.213721)
							(end -0.254 -0.1778)
						)
					)
					(width 0)
					(fill yes)
				)
			)
		)
	)
)
